# S9S_MB_2U (Grand Teton) — schematic netlist excerpt (pin names and nets, part order shuffled) for the footprints in the layout excerpt that follows; sources: Cadence DE-HDL packaged netlist, KiCad conversion of 03242023_DA0F0TMBIJ0_F0T_Motherboard_J_brd_V01_OCP.brd

R2387  Q_RES  0 5% CHIP  pkg 0402LF  page 300 : A = PWRGD_PVNN_MAIN_CPU1_R ; B = PWRGD_PVNN_MAIN_CPU1
C21  Q_CAP  10UF 16V 10% X6S  pkg C0805  page 88 : A = P12V_S3_AUX_CPU0_NVDIMM ; B = GND

(kicad_pcb
	(version 20260206)
	(generator "pcbnew")
	(generator_version "10.0")
	(general
		(thickness 1.6)
		(legacy_teardrops no)
	)
	(paper "A4")
	(title_block
		(title "03242023_DA0F0TMBIJ0_F0T_Motherboard_J_brd_V01_OCP.brd")
		(comment 1 "Grand Teton / footprints 4517-4518 of 6105")
	)
	(layers
		(0 "F.Cu" signal "TOP")
		(4 "In1.Cu" signal "GND")
		(6 "In2.Cu" signal "IN1")
		(8 "In3.Cu" signal "GND1")
		(10 "In4.Cu" signal "IN2")
		(12 "In5.Cu" signal "GND2")
		(14 "In6.Cu" signal "IN3")
		(16 "In7.Cu" signal "GND3")
		(18 "In8.Cu" signal "VCC")
		(20 "In9.Cu" signal "VCC1")
		(22 "In10.Cu" signal "GND4")
		(24 "In11.Cu" signal "IN4")
		(26 "In12.Cu" signal "GND5")
		(28 "In13.Cu" signal "IN5")
		(30 "In14.Cu" signal "GND6")
		(32 "In15.Cu" signal "IN6")
		(34 "In16.Cu" signal "GND7")
		(2 "B.Cu" signal "BOTTOM")
		(9 "F.Adhes" user "F.Adhesive")
		(11 "B.Adhes" user "B.Adhesive")
		(13 "F.Paste" user "Package Geometry/Pastemask Top")
		(15 "B.Paste" user "Package Geometry/Pastemask Bottom")
		(5 "F.SilkS" user "Ref Des/Silkscreen Top")
		(7 "B.SilkS" user "Ref Des/Silkscreen Bottom")
		(1 "F.Mask" user "Board Geometry/Soldermask Top")
		(3 "B.Mask" user "Board Geometry/Soldermask Bottom")
		(17 "Dwgs.User" user "User.Drawings")
		(19 "Cmts.User" user "User.Comments")
		(21 "Eco1.User" user "User.Eco1")
		(23 "Eco2.User" user "User.Eco2")
		(25 "Edge.Cuts" user "Board Geometry/Outline")
		(27 "Margin" user)
		(31 "F.CrtYd" user "Package Geometry/Place Bound Top")
		(29 "B.CrtYd" user "Package Geometry/Place Bound Bottom")
		(35 "F.Fab" user "Ref Des/Assembly Top")
		(33 "B.Fab" user "Ref Des/Assembly Bottom")
	)
	(footprint ""
		(layer "B.Cu")
		(at 24.352504 -175.819562 90)
		(property "Reference" "R2387"
			(at 0 0 90)
			(layer "B.SilkS")
			(hide yes)
			(effects
				(font
					(size 1.27 1.27)
				)
				(justify mirror)
			)
		)
		(property "Value" ""
			(at 0 0 90)
			(layer "B.Fab")
			(effects
				(font
					(size 1.27 1.27)
				)
				(justify mirror)
			)
		)
		(duplicate_pad_numbers_are_jumpers no)
		(fp_line
			(start 0.7874 -0.4064)
			(end -0.7874 -0.4064)
			(stroke
				(width 0.1524)
				(type default)
			)
			(layer "B.SilkS")
		)
		(fp_line
			(start -0.7874 -0.4064)
			(end -0.7874 0.4064)
			(stroke
				(width 0.1524)
				(type default)
			)
			(layer "B.SilkS")
		)
		(fp_line
			(start 0.7874 0.4064)
			(end 0.7874 -0.4064)
			(stroke
				(width 0.1524)
				(type default)
			)
			(layer "B.SilkS")
		)
		(fp_line
			(start -0.7874 0.4064)
			(end 0.7874 0.4064)
			(stroke
				(width 0.1524)
				(type default)
			)
			(layer "B.SilkS")
		)
		(fp_line
			(start 0.67945 -0.305054)
			(end 0.12065 -0.305054)
			(stroke
				(width 0.1)
				(type default)
			)
			(layer "B.Fab")
		)
		(fp_line
			(start 0.12065 -0.305054)
			(end 0.12065 -0.2794)
			(stroke
				(width 0.1)
				(type default)
			)
			(layer "B.Fab")
		)
		(fp_line
			(start -0.12065 -0.3048)
			(end -0.67945 -0.3048)
			(stroke
				(width 0.1)
				(type default)
			)
			(layer "B.Fab")
		)
		(fp_line
			(start -0.67945 -0.3048)
			(end -0.67945 0.3048)
			(stroke
				(width 0.1)
				(type default)
			)
			(layer "B.Fab")
		)
		(fp_line
			(start 0.12065 -0.2794)
			(end -0.12065 -0.2794)
			(stroke
				(width 0.1)
				(type default)
			)
			(layer "B.Fab")
		)
		(fp_line
			(start -0.12065 -0.2794)
			(end -0.12065 -0.3048)
			(stroke
				(width 0.1)
				(type default)
			)
			(layer "B.Fab")
		)
		(fp_line
			(start 0.12065 0.2794)
			(end 0.12065 0.3048)
			(stroke
				(width 0.1)
				(type default)
			)
			(layer "B.Fab")
		)
		(fp_line
			(start -0.120396 0.2794)
			(end 0.12065 0.2794)
			(stroke
				(width 0.1)
				(type default)
			)
			(layer "B.Fab")
		)
		(fp_line
			(start 0.67945 0.3048)
			(end 0.67945 -0.305054)
			(stroke
				(width 0.1)
				(type default)
			)
			(layer "B.Fab")
		)
		(fp_line
			(start 0.12065 0.3048)
			(end 0.67945 0.3048)
			(stroke
				(width 0.1)
				(type default)
			)
			(layer "B.Fab")
		)
		(fp_line
			(start -0.120396 0.3048)
			(end -0.120396 0.2794)
			(stroke
				(width 0.1)
				(type default)
			)
			(layer "B.Fab")
		)
		(fp_line
			(start -0.67945 0.3048)
			(end -0.120396 0.3048)
			(stroke
				(width 0.1)
				(type default)
			)
			(layer "B.Fab")
		)
		(pad "1" smd circle
			(at 0.40005 0 270)
			(size 0 0)
			(layers "B.Cu" "B.Mask" "B.Paste")
			(net "PWRGD_PVNN_MAIN_CPU1_R")
		)
		(pad "2" smd circle
			(at -0.40005 0 270)
			(size 0 0)
			(layers "B.Cu" "B.Mask" "B.Paste")
			(net "PWRGD_PVNN_MAIN_CPU1")
		)
	)
	(footprint ""
		(layer "B.Cu")
		(at 260.157214 -321.549776 -90)
		(property "Reference" "C21"
			(at 0 0 90)
			(layer "B.SilkS")
			(hide yes)
			(effects
				(font
					(size 1.27 1.27)
				)
				(justify mirror)
			)
		)
		(property "Value" ""
			(at 0 0 90)
			(layer "B.Fab")
			(effects
				(font
					(size 1.27 1.27)
				)
				(justify mirror)
			)
		)
		(duplicate_pad_numbers_are_jumpers no)
		(fp_line
			(start -1.524 0.762)
			(end 1.524 0.762)
			(stroke
				(width 0.1524)
				(type default)
			)
			(layer "B.SilkS")
		)
		(fp_line
			(start 1.524 0.762)
			(end 1.524 -0.762)
			(stroke
				(width 0.1524)
				(type default)
			)
			(layer "B.SilkS")
		)
		(fp_line
			(start -1.524 -0.762)
			(end -1.524 0.762)
			(stroke
				(width 0.1524)
				(type default)
			)
			(layer "B.SilkS")
		)
		(fp_line
			(start 1.524 -0.762)
			(end -1.524 -0.762)
			(stroke
				(width 0.1524)
				(type default)
			)
			(layer "B.SilkS")
		)
		(fp_line
			(start -1.1049 0.724916)
			(end -1.1049 -0.724916)
			(stroke
				(width 0.1)
				(type default)
			)
			(layer "B.Fab")
		)
		(fp_line
			(start 1.1049 0.724916)
			(end -1.1049 0.724916)
			(stroke
				(width 0.1)
				(type default)
			)
			(layer "B.Fab")
		)
		(fp_line
			(start -1.1049 -0.724916)
			(end 1.1049 -0.724916)
			(stroke
				(width 0.1)
				(type default)
			)
			(layer "B.Fab")
		)
		(fp_line
			(start 1.1049 -0.724916)
			(end 1.1049 0.724916)
			(stroke
				(width 0.1)
				(type default)
			)
			(layer "B.Fab")
		)
		(pad "1" smd rect
			(at 0.889 0 270)
			(size 1.016 1.27)
			(layers "B.Cu" "B.Mask" "B.Paste")
			(net "P12V_S3_AUX_CPU0_NVDIMM")
		)
		(pad "2" smd rect
			(at -0.889 0 270)
			(size 1.016 1.27)
			(layers "B.Cu" "B.Mask" "B.Paste")
			(net "GND")
		)
	)
)
